# BASEBOARD_FAB2 (Tioga Pass) — schematic netlist excerpt (pin names and nets, part order shuffled) for the footprints in the layout excerpt that follows; sources: Cadence DE-HDL packaged netlist, KiCad conversion of Wiwynn_Tioga_Pass_MB.brd

C4E25  SC1U10V2KX-4-GP  10%  pkg SMD-BCG6  page 202 : \1\ = P5V_STBY ; \2\ = GND

Q8G1  MOSFET_N  BSZ019N03LS NFET  pkg LCC3  page 198
  SRC  = P3V3
  GATE  = P3V3_SWITCH_G
  DRN  = P3V3_STBY

C5G111  CAP_A  22.0UF 4V 20% X6S  pkg 0603V  page 243 : A = PVDDQ_KLM ; B = GND

(kicad_pcb
	(version 20260206)
	(generator "pcbnew")
	(generator_version "10.0")
	(general
		(thickness 1.6)
		(legacy_teardrops no)
	)
	(paper "A4")
	(title_block
		(title "Wiwynn_Tioga_Pass_MB.brd")
		(comment 1 "Tioga Pass / footprints 3133-3135 of 4770")
	)
	(layers
		(0 "F.Cu" signal "TOP")
		(4 "In1.Cu" signal "L2GND")
		(6 "In2.Cu" signal "L3")
		(8 "In3.Cu" signal "L4GND")
		(10 "In4.Cu" signal "L5")
		(12 "In5.Cu" signal "L6GND")
		(14 "In6.Cu" signal "L7VCC")
		(16 "In7.Cu" signal "L8VCC")
		(18 "In8.Cu" signal "L9GND")
		(20 "In9.Cu" signal "L10")
		(22 "In10.Cu" signal "L11GND")
		(24 "In11.Cu" signal "L12")
		(26 "In12.Cu" signal "L13GND")
		(2 "B.Cu" signal "BOTTOM")
		(9 "F.Adhes" user "F.Adhesive")
		(11 "B.Adhes" user "B.Adhesive")
		(13 "F.Paste" user "Package Geometry/Pastemask Top")
		(15 "B.Paste" user "Package Geometry/Pastemask Bottom")
		(5 "F.SilkS" user "Ref Des/Silkscreen Top")
		(7 "B.SilkS" user "Ref Des/Silkscreen Bottom")
		(1 "F.Mask" user "Board Geometry/Soldermask Top")
		(3 "B.Mask" user "Board Geometry/Soldermask Bottom")
		(17 "Dwgs.User" user "User.Drawings")
		(19 "Cmts.User" user "User.Comments")
		(21 "Eco1.User" user "User.Eco1")
		(23 "Eco2.User" user "User.Eco2")
		(25 "Edge.Cuts" user "Board Geometry/Outline")
		(27 "Margin" user)
		(31 "F.CrtYd" user "Package Geometry/Place Bound Top")
		(29 "B.CrtYd" user "Package Geometry/Place Bound Bottom")
		(35 "F.Fab" user "Ref Des/Assembly Top")
		(33 "B.Fab" user "Ref Des/Assembly Bottom")
	)
	(footprint ""
		(layer "B.Cu")
		(at 88.392 -140.208 90)
		(property "Reference" "C5G111"
			(at -1.14681 0.76708 180)
			(unlocked yes)
			(layer "B.SilkS")
			(effects
				(font
					(size 0.7874 0.5842)
					(thickness 0.1524)
				)
				(justify mirror)
			)
		)
		(property "Value" ""
			(at 0 0 90)
			(layer "B.Fab")
			(effects
				(font
					(size 1.27 1.27)
				)
				(justify mirror)
			)
		)
		(duplicate_pad_numbers_are_jumpers no)
		(fp_rect
			(start -0.4953 -0.2032)
			(end 0.4953 1.6002)
			(stroke
				(width 0)
				(type default)
			)
			(fill no)
			(layer "B.CrtYd")
		)
		(fp_line
			(start 0.4953 -0.2032)
			(end -0.4953 -0.2032)
			(stroke
				(width 0.1)
				(type default)
			)
			(layer "B.Fab")
		)
		(fp_line
			(start -0.4953 -0.2032)
			(end -0.4953 1.6002)
			(stroke
				(width 0.1)
				(type default)
			)
			(layer "B.Fab")
		)
		(fp_line
			(start 0.4953 1.6002)
			(end 0.4953 -0.2032)
			(stroke
				(width 0.1)
				(type default)
			)
			(layer "B.Fab")
		)
		(fp_line
			(start -0.4953 1.6002)
			(end 0.4953 1.6002)
			(stroke
				(width 0.1)
				(type default)
			)
			(layer "B.Fab")
		)
		(pad "1" smd rect
			(at 0 0 270)
			(size 0.762 0.889)
			(layers "B.Cu" "B.Mask" "B.Paste")
			(net "PVDDQ_KLM")
		)
		(pad "2" smd rect
			(at 0 1.397 270)
			(size 0.762 0.889)
			(layers "B.Cu" "B.Mask" "B.Paste")
			(net "GND")
		)
		(zone
			(layer "B.Cu")
			(hatch none 0.5)
			(connect_pads
				(clearance 0)
			)
			(min_thickness 0.25)
			(keepout
				(tracks not_allowed)
				(vias allowed)
				(pads allowed)
				(copperpour not_allowed)
				(footprints allowed)
			)
			(placement
				(enabled no)
				(sheetname "")
			)
			(fill
				(thermal_gap 0.5)
				(thermal_bridge_width 0.5)
				(island_removal_mode 0)
			)
			(polygon
				(pts
					(xy 88.8365 -139.827) (xy 89.3445 -139.827) (xy 89.3445 -140.589) (xy 88.8365 -140.589)
				)
			)
		)
	)
	(footprint ""
		(layer "B.Cu")
		(at 467.20506 -16.392144)
		(property "Reference" "Q8G1"
			(at -1.9812 -1.92405 0)
			(unlocked yes)
			(layer "B.SilkS")
			(effects
				(font
					(size 0.7874 0.5842)
					(thickness 0.1524)
				)
				(justify left mirror)
			)
		)
		(property "Value" ""
			(at 0 0 0)
			(layer "B.Fab")
			(effects
				(font
					(size 1.27 1.27)
				)
				(justify mirror)
			)
		)
		(duplicate_pad_numbers_are_jumpers no)
		(fp_line
			(start 0.245364 -1.379982)
			(end -3.15468 -1.379982)
			(stroke
				(width 0.1524)
				(type default)
			)
			(layer "B.SilkS")
		)
		(fp_line
			(start 0.245364 2.020062)
			(end -3.15468 2.020062)
			(stroke
				(width 0.1524)
				(type default)
			)
			(layer "B.SilkS")
		)
		(fp_circle
			(center 0.84455 -0.216154)
			(end 0.97155 -0.216154)
			(stroke
				(width 0.254)
				(type default)
			)
			(fill no)
			(layer "B.SilkS")
		)
		(fp_poly
			(pts
				(xy -0.890016 -0.82296) (xy -0.890016 1.46304) (xy -3.404616 1.46304) (xy -3.404616 1.13284) (xy -2.617216 1.13284)
				(xy -2.617216 0.811022) (xy -3.404616 0.811022) (xy -3.404616 0.480822) (xy -2.617216 0.480822)
				(xy -2.617216 0.159258) (xy -3.404616 0.159258) (xy -3.404616 -0.170942) (xy -2.617216 -0.170942)
				(xy -2.617216 -0.49276) (xy -3.404616 -0.49276) (xy -3.404616 -0.82296)
			)
			(stroke
				(width 0)
				(type default)
			)
			(fill yes)
			(layer "B.Paste")
		)
		(fp_poly
			(pts
				(xy 0.245364 -1.379982) (xy 0.245364 2.020062) (xy -3.15468 2.020062) (xy -3.15468 -1.379982)
			)
			(stroke
				(width 0)
				(type default)
			)
			(fill no)
			(layer "B.CrtYd")
		)
		(fp_line
			(start -3.15468 -1.379982)
			(end -3.15468 2.020062)
			(stroke
				(width 0.1)
				(type default)
			)
			(layer "B.Fab")
		)
		(fp_line
			(start -3.15468 2.020062)
			(end 0.245364 2.020062)
			(stroke
				(width 0.1)
				(type default)
			)
			(layer "B.Fab")
		)
		(fp_line
			(start 0.245364 -1.379982)
			(end -3.15468 -1.379982)
			(stroke
				(width 0.1)
				(type default)
			)
			(layer "B.Fab")
		)
		(fp_line
			(start 0.245364 2.020062)
			(end 0.245364 -1.379982)
			(stroke
				(width 0.1)
				(type default)
			)
			(layer "B.Fab")
		)
		(fp_circle
			(center 0.94996 -1.512316)
			(end 1.07696 -1.512316)
			(stroke
				(width 0.254)
				(type default)
			)
			(fill no)
			(layer "B.Fab")
		)
		(pad "1" smd custom
			(at 0 0 180)
			(size 0.24765 0.24765)
			(layers "B.Cu" "B.Mask" "B.Paste")
			(net "P3V3")
			(options
				(clearance outline)
				(anchor circle)
			)
			(primitives
				(gr_poly
					(pts
						(xy 0.4953 -0.8255) (xy 0.4953 0.8255) (xy -0.4953 0.8255) (xy -0.4953 0.4953) (xy 0.0127 0.4953)
						(xy 0.0127 0.1651) (xy -0.4953 0.1651) (xy -0.4953 -0.1651) (xy 0.0127 -0.1651) (xy 0.0127 -0.4953)
						(xy -0.4953 -0.4953) (xy -0.4953 -0.8255)
					)
					(width 0)
					(fill yes)
				)
			)
		)
		(pad "4" smd rect
			(at 0 1.30048 180)
			(size 0.9906 0.3302)
			(layers "B.Cu" "B.Mask" "B.Paste")
			(net "P3V3_SWITCH_G")
		)
		(pad "5" smd custom
			(at -2.147316 0.32004 180)
			(size 0.5715 0.5715)
			(layers "B.Cu" "B.Mask" "B.Paste")
			(net "P3V3_STBY")
			(options
				(clearance outline)
				(anchor circle)
			)
			(primitives
				(gr_poly
					(pts
						(xy -1.2573 1.143) (xy -1.2573 -1.143) (xy 1.2573 -1.143) (xy 1.2573 -0.8128) (xy 0.4699 -0.8128)
						(xy 0.4699 -0.490982) (xy 1.2573 -0.490982) (xy 1.2573 -0.160782) (xy 0.4699 -0.160782) (xy 0.4699 0.160782)
						(xy 1.2573 0.160782) (xy 1.2573 0.490982) (xy 0.4699 0.490982) (xy 0.4699 0.8128) (xy 1.2573 0.8128)
						(xy 1.2573 1.143)
					)
					(width 0)
					(fill yes)
				)
			)
		)
	)
	(footprint ""
		(layer "B.Cu")
		(at 198.623428 -61.285882 90)
		(property "Reference" "C4E25"
			(at 0 0 90)
			(layer "B.SilkS")
			(hide yes)
			(effects
				(font
					(size 1.27 1.27)
				)
				(justify mirror)
			)
		)
		(property "Value" "*"
			(at -1.1811 -2.8194 90)
			(unlocked yes)
			(layer "B.Fab")
			(hide yes)
			(effects
				(font
					(size 1.27 1.016)
					(thickness 0.1524)
				)
				(justify mirror)
			)
		)
		(property "Device Type" "SC1U10V2KX-4-GP_SMD-BCG6-SC1U1A"
			(at -1.1811 -4.3434 90)
			(unlocked yes)
			(layer "B.Fab")
			(hide yes)
			(effects
				(font
					(size 1.27 1.016)
					(thickness 0.1524)
				)
				(justify mirror)
			)
		)
		(duplicate_pad_numbers_are_jumpers no)
		(fp_rect
			(start 0.4318 0.9525)
			(end -0.4318 -0.9525)
			(stroke
				(width 0)
				(type default)
			)
			(fill no)
			(layer "B.CrtYd")
		)
		(fp_rect
			(start 0.4318 0.9525)
			(end -0.4318 -0.9525)
			(stroke
				(width 0)
				(type default)
			)
			(fill no)
			(layer "B.Fab")
		)
		(pad "1" smd custom
			(at 0 -0.4445 270)
			(size 0.1524 0.1524)
			(layers "B.Cu" "B.Mask" "B.Paste")
			(net "P5V_STBY")
			(options
				(clearance outline)
				(anchor circle)
			)
			(primitives
				(gr_poly
					(pts
						(arc
							(start 0.3048 0.2032)
							(mid 0.275042 0.275042)
							(end 0.2032 0.3048)
						)
						(arc
							(start -0.2032 0.3048)
							(mid -0.275042 0.275042)
							(end -0.3048 0.2032)
						)
						(arc
							(start -0.3048 -0.2032)
							(mid -0.275042 -0.275042)
							(end -0.2032 -0.3048)
						)
						(arc
							(start 0.2032 -0.3048)
							(mid 0.275042 -0.275042)
							(end 0.3048 -0.2032)
						)
					)
					(width 0)
					(fill yes)
				)
			)
		)
		(pad "2" smd custom
			(at 0 0.4445 270)
			(size 0.1524 0.1524)
			(layers "B.Cu" "B.Mask" "B.Paste")
			(net "GND")
			(options
				(clearance outline)
				(anchor circle)
			)
			(primitives
				(gr_poly
					(pts
						(arc
							(start 0.3048 0.2032)
							(mid 0.275042 0.275042)
							(end 0.2032 0.3048)
						)
						(arc
							(start -0.2032 0.3048)
							(mid -0.275042 0.275042)
							(end -0.3048 0.2032)
						)
						(arc
							(start -0.3048 -0.2032)
							(mid -0.275042 -0.275042)
							(end -0.2032 -0.3048)
						)
						(arc
							(start 0.2032 -0.3048)
							(mid 0.275042 -0.275042)
							(end 0.3048 -0.2032)
						)
					)
					(width 0)
					(fill yes)
				)
			)
		)
	)
)
